(kicad_pcb
	(version 20241229)
	(generator "pcbnew")
	(generator_version "9.0")
	(general
		(thickness 1.62)
		(legacy_teardrops no)
	)
	(paper "A4")
	(title_block
		(title "OCuLink to 10GbE adapter")
		(date "2026-02-23")
		(rev "1.1.0")
		(company "Antmicro Ltd")
		(comment 1 "www.antmicro.com")
		(comment 9 "footprints 301-305 of 510")
	)
	(layers
		(0 "F.Cu" signal)
		(4 "In1.Cu" signal)
		(6 "In2.Cu" signal)
		(8 "In3.Cu" signal)
		(10 "In4.Cu" signal)
		(12 "In5.Cu" signal)
		(14 "In6.Cu" signal)
		(2 "B.Cu" signal)
		(9 "F.Adhes" user "F.Adhesive")
		(11 "B.Adhes" user "B.Adhesive")
		(13 "F.Paste" user)
		(15 "B.Paste" user)
		(5 "F.SilkS" user "F.Silkscreen")
		(7 "B.SilkS" user "B.Silkscreen")
		(1 "F.Mask" user)
		(3 "B.Mask" user)
		(17 "Dwgs.User" user "User.Drawings")
		(19 "Cmts.User" user "User.Comments")
		(21 "Eco1.User" user "User.Eco1")
		(23 "Eco2.User" user "User.Eco2")
		(25 "Edge.Cuts" user)
		(27 "Margin" user)
		(31 "F.CrtYd" user "F.Courtyard")
		(29 "B.CrtYd" user "B.Courtyard")
		(35 "F.Fab" user)
		(33 "B.Fab" user)
	)
	(footprint "antmicro-footprints:Tag-Connect_TC2050-IDC-NL_2x5_P1.27mm"
		(layer "B.Cu")
		(at 55.7 81.65 180)
		(property "Reference" "J7"
			(at 0.1 2.3 0)
			(layer "B.SilkS")
			(effects
				(font
					(size 0.7 0.7)
					(thickness 0.15)
				)
				(justify left bottom mirror)
			)
		)
		(property "Value" "Tag-Connect_TC2050-IDC-NL_2x5_P1.27mm"
			(at 0 -4.4 0)
			(layer "B.Fab")
			(hide yes)
			(effects
				(font
					(size 0.7 0.7)
					(thickness 0.15)
				)
				(justify left bottom mirror)
			)
		)
		(property "Datasheet" "https://www.tag-connect.com/wp-content/uploads/bsk-pdf-manager/TC2050-IDC-NL_Datasheet_8.pdf"
			(at 0 0 0)
			(layer "B.Fab")
			(hide yes)
			(effects
				(font
					(size 1.27 1.27)
					(thickness 0.15)
				)
				(justify mirror)
			)
		)
		(property "Description" "Tag Connect 2x5 1.27mm terminal"
			(at 0 0 0)
			(layer "B.Fab")
			(hide yes)
			(effects
				(font
					(size 1.27 1.27)
					(thickness 0.15)
				)
				(justify mirror)
			)
		)
		(property "MPN" "TC2050-IDC-NL"
			(at 0 0 180)
			(unlocked yes)
			(layer "B.Fab")
			(hide yes)
			(effects
				(font
					(size 1 1)
					(thickness 0.15)
				)
				(justify mirror)
			)
		)
		(property "Manufacturer" "Tag Connect"
			(at 0 0 180)
			(unlocked yes)
			(layer "B.Fab")
			(hide yes)
			(effects
				(font
					(size 1 1)
					(thickness 0.15)
				)
				(justify mirror)
			)
		)
		(property "Author" "Antmicro"
			(at 0 0 180)
			(unlocked yes)
			(layer "B.Fab")
			(hide yes)
			(effects
				(font
					(size 1 1)
					(thickness 0.15)
				)
				(justify mirror)
			)
		)
		(property "License" "Apache-2.0"
			(at 0 0 180)
			(unlocked yes)
			(layer "B.Fab")
			(hide yes)
			(effects
				(font
					(size 1 1)
					(thickness 0.15)
				)
				(justify mirror)
			)
		)
		(sheetname "/X710-AT2 PCIe/")
		(sheetfile "x710-at2-pcie.kicad_sch")
		(attr exclude_from_pos_files exclude_from_bom dnp)
		(fp_line
			(start 5.1 1.7)
			(end 5.1 -1.7)
			(stroke
				(width 0.15)
				(type solid)
			)
			(layer "B.SilkS")
		)
		(fp_line
			(start 4.7 2.05)
			(end 5.1 1.7)
			(stroke
				(width 0.15)
				(type solid)
			)
			(layer "B.SilkS")
		)
		(fp_line
			(start 4.7 -2.049)
			(end 5.1 -1.7)
			(stroke
				(width 0.15)
				(type solid)
			)
			(layer "B.SilkS")
		)
		(fp_line
			(start 4.7 -2.049)
			(end -2.3 -2.049)
			(stroke
				(width 0.15)
				(type solid)
			)
			(layer "B.SilkS")
		)
		(fp_line
			(start -2.2 2.05)
			(end 4.7 2.05)
			(stroke
				(width 0.15)
				(type solid)
			)
			(layer "B.SilkS")
		)
		(fp_line
			(start -2.3 -2.049)
			(end -5.08 -0.8)
			(stroke
				(width 0.15)
				(type solid)
			)
			(layer "B.SilkS")
		)
		(fp_line
			(start -3.101 -1.269)
			(end -3.101 -0.4)
			(stroke
				(width 0.15)
				(type solid)
			)
			(layer "B.SilkS")
		)
		(fp_line
			(start -5.08 0.9)
			(end -2.2 2.05)
			(stroke
				(width 0.15)
				(type solid)
			)
			(layer "B.SilkS")
		)
		(fp_line
			(start -5.08 -0.8)
			(end -5.08 0.9)
			(stroke
				(width 0.15)
				(type solid)
			)
			(layer "B.SilkS")
		)
		(fp_line
			(start 5.32 1.8)
			(end 5.32 -1.8)
			(stroke
				(width 0.05)
				(type solid)
			)
			(layer "B.CrtYd")
		)
		(fp_line
			(start 4.8 2.3)
			(end 5.32 1.8)
			(stroke
				(width 0.05)
				(type solid)
			)
			(layer "B.CrtYd")
		)
		(fp_line
			(start 4.8 -2.29)
			(end 5.32 -1.8)
			(stroke
				(width 0.05)
				(type solid)
			)
			(layer "B.CrtYd")
		)
		(fp_line
			(start 4.8 -2.29)
			(end -2.4 -2.29)
			(stroke
				(width 0.05)
				(type solid)
			)
			(layer "B.CrtYd")
		)
		(fp_line
			(start -2.3 2.3)
			(end 4.8 2.3)
			(stroke
				(width 0.05)
				(type solid)
			)
			(layer "B.CrtYd")
		)
		(fp_line
			(start -2.4 -2.29)
			(end -5.33 -1)
			(stroke
				(width 0.05)
				(type solid)
			)
			(layer "B.CrtYd")
		)
		(fp_line
			(start -5.33 1.1)
			(end -2.3 2.3)
			(stroke
				(width 0.05)
				(type solid)
			)
			(layer "B.CrtYd")
		)
		(fp_line
			(start -5.33 -1)
			(end -5.33 1.1)
			(stroke
				(width 0.05)
				(type solid)
			)
			(layer "B.CrtYd")
		)
		(pad "" np_thru_hole circle
			(at -3.81 0 180)
			(size 0.9906 0.9906)
			(drill 0.9906)
			(layers "*.Cu" "*.Mask")
		)
		(pad "" np_thru_hole circle
			(at 3.809 -1.015 180)
			(size 0.9906 0.9906)
			(drill 0.9906)
			(layers "*.Cu" "*.Mask")
		)
		(pad "" np_thru_hole circle
			(at 3.809 1.016 180)
			(size 0.9906 0.9906)
			(drill 0.9906)
			(layers "*.Cu" "*.Mask")
		)
		(pad "1" connect circle
			(at -2.54 -0.634 180)
			(size 0.7874 0.7874)
			(layers "B.Cu" "B.Mask")
			(net 147 "unconnected-(J7-Pad1)")
			(pinfunction "3V3")
			(pintype "passive+no_connect")
		)
		(pad "2" connect circle
			(at -1.27 -0.634 180)
			(size 0.7874 0.7874)
			(layers "B.Cu" "B.Mask")
			(net 4 "/X710-AT2 PCIe/PCIe_JTAG.JTMS")
			(pinfunction "JTAG_TMS")
			(pintype "passive")
		)
		(pad "3" connect circle
			(at 0 -0.634 180)
			(size 0.7874 0.7874)
			(layers "B.Cu" "B.Mask")
			(net 28 "GND")
			(pinfunction "GND")
			(pintype "passive")
		)
		(pad "4" connect circle
			(at 1.269 -0.634 180)
			(size 0.7874 0.7874)
			(layers "B.Cu" "B.Mask")
			(net 16 "/X710-AT2 PCIe/PCIe_JTAG.JTCK")
			(pinfunction "JTAG_TCK")
			(pintype "passive")
		)
		(pad "5" connect circle
			(at 2.539 -0.634 180)
			(size 0.7874 0.7874)
			(layers "B.Cu" "B.Mask")
			(net 28 "GND")
			(pinfunction "GND")
			(pintype "passive")
		)
		(pad "6" connect circle
			(at 2.539 0.635 180)
			(size 0.7874 0.7874)
			(layers "B.Cu" "B.Mask")
			(net 8 "/X710-AT2 PCIe/PCIe_JTAG.JTDO")
			(pinfunction "JTAG_TDO")
			(pintype "passive")
		)
		(pad "7" connect circle
			(at 1.269 0.635 180)
			(size 0.7874 0.7874)
			(layers "B.Cu" "B.Mask")
			(net 148 "unconnected-(J7-Pad7)")
			(pinfunction "NC")
			(pintype "passive")
		)
		(pad "8" connect circle
			(at 0 0.635 180)
			(size 0.7874 0.7874)
			(layers "B.Cu" "B.Mask")
			(net 11 "/X710-AT2 PCIe/PCIe_JTAG.JTDI")
			(pinfunction "JTAG_TDI")
			(pintype "passive")
		)
		(pad "9" connect circle
			(at -1.27 0.635 180)
			(size 0.7874 0.7874)
			(layers "B.Cu" "B.Mask")
			(net 28 "GND")
			(pinfunction "GND")
			(pintype "passive")
		)
		(pad "10" connect circle
			(at -2.54 0.635 180)
			(size 0.7874 0.7874)
			(layers "B.Cu" "B.Mask")
			(net 15 "/X710-AT2 PCIe/PCIe_JTAG.~{JRST}")
			(pinfunction "JTAG_~{RESET}")
			(pintype "passive")
		)
	)
	(footprint "antmicro-footprints:C_0402_1005Metric"
		(layer "B.Cu")
		(at 87.225 102 90)
		(descr "Capacitor SMD 0402")
		(tags "capacitor SMD 0402")
		(property "Reference" "C98"
			(at 9.09 -0.447343 90)
			(layer "B.SilkS")
			(effects
				(font
					(size 0.7 0.7)
					(thickness 0.15)
				)
				(justify right top mirror)
			)
		)
		(property "Value" "C_1u_25V_0402"
			(at -1.022927 -2.155213 90)
			(layer "B.Fab")
			(hide yes)
			(effects
				(font
					(size 0.7 0.7)
					(thickness 0.15)
				)
				(justify right top mirror)
			)
		)
		(property "Datasheet" "https://www.murata.com/products/productdetail?partno=GRM155R61E105KE11%23"
			(at 0 0 90)
			(layer "B.Fab")
			(hide yes)
			(effects
				(font
					(size 1.27 1.27)
					(thickness 0.15)
				)
				(justify mirror)
			)
		)
		(property "Description" "SMD Multilayer Ceramic Capacitor, 1 µF, 25 V, 0402 [1005 Metric], ± 10%, X5R, GRM Series"
			(at 0 0 90)
			(layer "B.Fab")
			(hide yes)
			(effects
				(font
					(size 1.27 1.27)
					(thickness 0.15)
				)
				(justify mirror)
			)
		)
		(property "MPN" "GRM155R61E105KE11J"
			(at 0 0 90)
			(unlocked yes)
			(layer "B.Fab")
			(hide yes)
			(effects
				(font
					(size 1 1)
					(thickness 0.15)
				)
				(justify mirror)
			)
		)
		(property "Manufacturer" "Murata"
			(at 0 0 90)
			(unlocked yes)
			(layer "B.Fab")
			(hide yes)
			(effects
				(font
					(size 1 1)
					(thickness 0.15)
				)
				(justify mirror)
			)
		)
		(property "License" "Apache-2.0"
			(at 0 0 90)
			(unlocked yes)
			(layer "B.Fab")
			(hide yes)
			(effects
				(font
					(size 1 1)
					(thickness 0.15)
				)
				(justify mirror)
			)
		)
		(property "Author" "Antmicro"
			(at 0 0 90)
			(unlocked yes)
			(layer "B.Fab")
			(hide yes)
			(effects
				(font
					(size 1 1)
					(thickness 0.15)
				)
				(justify mirror)
			)
		)
		(property "Val" "1u"
			(at 0 0 90)
			(unlocked yes)
			(layer "B.Fab")
			(hide yes)
			(effects
				(font
					(size 1 1)
					(thickness 0.15)
				)
				(justify mirror)
			)
		)
		(property "Voltage" "25V"
			(at 0 0 90)
			(unlocked yes)
			(layer "B.Fab")
			(hide yes)
			(effects
				(font
					(size 1 1)
					(thickness 0.15)
				)
				(justify mirror)
			)
		)
		(property "Dielectric" "X5R"
			(at 0 0 90)
			(unlocked yes)
			(layer "B.Fab")
			(hide yes)
			(effects
				(font
					(size 1 1)
					(thickness 0.15)
				)
				(justify mirror)
			)
		)
		(sheetname "/X710-AT2 power/")
		(sheetfile "x710-at2-power.kicad_sch")
		(attr smd)
		(fp_rect
			(start -0.925 0.47)
			(end 0.925 -0.47)
			(stroke
				(width 0.05)
				(type default)
			)
			(fill no)
			(layer "B.CrtYd")
		)
		(fp_line
			(start 0.504 -0.248)
			(end -0.494 -0.248)
			(stroke
				(width 0.15)
				(type solid)
			)
			(layer "B.Fab")
		)
		(fp_line
			(start -0.494 -0.248)
			(end -0.494 0.25)
			(stroke
				(width 0.15)
				(type solid)
			)
			(layer "B.Fab")
		)
		(fp_line
			(start 0.504 0.25)
			(end 0.504 -0.248)
			(stroke
				(width 0.15)
				(type solid)
			)
			(layer "B.Fab")
		)
		(fp_line
			(start -0.494 0.25)
			(end 0.504 0.25)
			(stroke
				(width 0.15)
				(type solid)
			)
			(layer "B.Fab")
		)
		(pad "1" smd roundrect
			(at -0.48 0 90)
			(size 0.59 0.64)
			(layers "B.Cu" "B.Mask" "B.Paste")
			(roundrect_rratio 0.25)
			(net 28 "GND")
			(pintype "passive")
		)
		(pad "2" smd roundrect
			(at 0.48 0 90)
			(size 0.59 0.64)
			(layers "B.Cu" "B.Mask" "B.Paste")
			(roundrect_rratio 0.25)
			(net 1 "VCCA")
			(pintype "passive")
		)
	)
	(footprint "antmicro-footprints:TP_SMD_0.75mm"
		(layer "B.Cu")
		(at 110.95 69.1 90)
		(property "Reference" "TP15"
			(at 0.598685 0.625533 180)
			(layer "B.SilkS")
			(effects
				(font
					(size 0.7 0.7)
					(thickness 0.15)
				)
				(justify right top mirror)
			)
		)
		(property "Value" "TP_0.75mm_SMD"
			(at 0 -1.2 90)
			(layer "B.Fab")
			(hide yes)
			(effects
				(font
					(size 0.7 0.7)
					(thickness 0.15)
				)
				(justify right top mirror)
			)
		)
		(property "Description" "SMT test point"
			(at 0 0 90)
			(layer "B.Fab")
			(hide yes)
			(effects
				(font
					(size 1.27 1.27)
					(thickness 0.15)
				)
				(justify mirror)
			)
		)
		(property "MPN" ""
			(at 0 0 90)
			(unlocked yes)
			(layer "B.Fab")
			(hide yes)
			(effects
				(font
					(size 1 1)
					(thickness 0.15)
				)
				(justify mirror)
			)
		)
		(property "Manufacturer" ""
			(at 0 0 90)
			(unlocked yes)
			(layer "B.Fab")
			(hide yes)
			(effects
				(font
					(size 1 1)
					(thickness 0.15)
				)
				(justify mirror)
			)
		)
		(property "Author" "Antmicro"
			(at 0 0 90)
			(unlocked yes)
			(layer "B.Fab")
			(hide yes)
			(effects
				(font
					(size 1 1)
					(thickness 0.15)
				)
				(justify mirror)
			)
		)
		(property "License" "Apache-2.0"
			(at 0 0 90)
			(unlocked yes)
			(layer "B.Fab")
			(hide yes)
			(effects
				(font
					(size 1 1)
					(thickness 0.15)
				)
				(justify mirror)
			)
		)
		(sheetname "/OCuLink/")
		(sheetfile "oculink.kicad_sch")
		(attr exclude_from_pos_files exclude_from_bom)
		(fp_circle
			(center 0 0)
			(end 0.475 0)
			(stroke
				(width 0.05)
				(type default)
			)
			(fill no)
			(layer "B.CrtYd")
		)
		(pad "1" smd circle
			(at 0 0 90)
			(size 0.75 0.75)
			(layers "B.Cu" "B.Mask")
			(net 321 "/OCuLink/~{CPRSNT}_R")
			(pinfunction "1")
			(pintype "passive")
		)
	)
	(footprint "antmicro-footprints:R_0402_1005Metric"
		(layer "B.Cu")
		(at 96.45 106.1 180)
		(descr "Resistor SMD 0402")
		(tags "resistor SMD 0402")
		(property "Reference" "R84"
			(at -0.9 0.261111 0)
			(layer "B.SilkS")
			(effects
				(font
					(size 0.7 0.7)
					(thickness 0.15)
				)
				(justify right top mirror)
			)
		)
		(property "Value" "R_22R_0402"
			(at -1.011843 -1.772047 0)
			(layer "B.Fab")
			(hide yes)
			(effects
				(font
					(size 0.7 0.7)
					(thickness 0.15)
				)
				(justify left bottom mirror)
			)
		)
		(property "Datasheet" "https://www.bourns.com/docs/product-datasheets/cr.pdf"
			(at 0 0 0)
			(layer "B.Fab")
			(hide yes)
			(effects
				(font
					(size 1.27 1.27)
					(thickness 0.15)
				)
				(justify mirror)
			)
		)
		(property "Description" "SMD Chip Resistor, 22 ohm, ± 1%, 62.5 mW, 0402 [1005 Metric], Thick Film, General Purpose"
			(at 0 0 0)
			(layer "B.Fab")
			(hide yes)
			(effects
				(font
					(size 1.27 1.27)
					(thickness 0.15)
				)
				(justify mirror)
			)
		)
		(property "MPN" "CR0402-FX-22R0GLF"
			(at 0 0 180)
			(unlocked yes)
			(layer "B.Fab")
			(hide yes)
			(effects
				(font
					(size 1 1)
					(thickness 0.15)
				)
				(justify mirror)
			)
		)
		(property "Manufacturer" "Bourns"
			(at 0 0 180)
			(unlocked yes)
			(layer "B.Fab")
			(hide yes)
			(effects
				(font
					(size 1 1)
					(thickness 0.15)
				)
				(justify mirror)
			)
		)
		(property "License" "Apache-2.0"
			(at 0 0 180)
			(unlocked yes)
			(layer "B.Fab")
			(hide yes)
			(effects
				(font
					(size 1 1)
					(thickness 0.15)
				)
				(justify mirror)
			)
		)
		(property "Author" "Antmicro"
			(at 0 0 180)
			(unlocked yes)
			(layer "B.Fab")
			(hide yes)
			(effects
				(font
					(size 1 1)
					(thickness 0.15)
				)
				(justify mirror)
			)
		)
		(property "Val" "22R"
			(at 0 0 180)
			(unlocked yes)
			(layer "B.Fab")
			(hide yes)
			(effects
				(font
					(size 1 1)
					(thickness 0.15)
				)
				(justify mirror)
			)
		)
		(property "Tolerance" "1%"
			(at 0 0 180)
			(unlocked yes)
			(layer "B.Fab")
			(hide yes)
			(effects
				(font
					(size 1 1)
					(thickness 0.15)
				)
				(justify mirror)
			)
		)
		(sheetname "/X710-AT2 Misc/")
		(sheetfile "x710-at2-mics.kicad_sch")
		(attr smd)
		(fp_rect
			(start -0.925 0.47)
			(end 0.925 -0.47)
			(stroke
				(width 0.05)
				(type default)
			)
			(fill no)
			(layer "B.CrtYd")
		)
		(fp_rect
			(start -0.5 0.25)
			(end 0.5 -0.25)
			(stroke
				(width 0.15)
				(type solid)
			)
			(fill no)
			(layer "B.Fab")
		)
		(pad "1" smd roundrect
			(at -0.48 0 180)
			(size 0.59 0.64)
			(layers "B.Cu" "B.Mask" "B.Paste")
			(roundrect_rratio 0.25)
			(net 365 "/X710-AT2 Misc/NCSI.CRS_DV")
			(pintype "passive")
		)
		(pad "2" smd roundrect
			(at 0.48 0 180)
			(size 0.59 0.64)
			(layers "B.Cu" "B.Mask" "B.Paste")
			(roundrect_rratio 0.25)
			(net 160 "Net-(U9D-NCSI_CRS_DV)")
			(pintype "passive")
		)
	)
	(footprint "antmicro-footprints:C_0402_1005Metric"
		(layer "B.Cu")
		(at 90.225 102 90)
		(descr "Capacitor SMD 0402")
		(tags "capacitor SMD 0402")
		(property "Reference" "C88"
			(at 9.09 -0.447343 90)
			(layer "B.SilkS")
			(effects
				(font
					(size 0.7 0.7)
					(thickness 0.15)
				)
				(justify right top mirror)
			)
		)
		(property "Value" "C_1u_25V_0402"
			(at -1.022927 -2.155213 90)
			(layer "B.Fab")
			(hide yes)
			(effects
				(font
					(size 0.7 0.7)
					(thickness 0.15)
				)
				(justify right top mirror)
			)
		)
		(property "Datasheet" "https://www.murata.com/products/productdetail?partno=GRM155R61E105KE11%23"
			(at 0 0 90)
			(layer "B.Fab")
			(hide yes)
			(effects
				(font
					(size 1.27 1.27)
					(thickness 0.15)
				)
				(justify mirror)
			)
		)
		(property "Description" "SMD Multilayer Ceramic Capacitor, 1 µF, 25 V, 0402 [1005 Metric], ± 10%, X5R, GRM Series"
			(at 0 0 90)
			(layer "B.Fab")
			(hide yes)
			(effects
				(font
					(size 1.27 1.27)
					(thickness 0.15)
				)
				(justify mirror)
			)
		)
		(property "MPN" "GRM155R61E105KE11J"
			(at 0 0 90)
			(unlocked yes)
			(layer "B.Fab")
			(hide yes)
			(effects
				(font
					(size 1 1)
					(thickness 0.15)
				)
				(justify mirror)
			)
		)
		(property "Manufacturer" "Murata"
			(at 0 0 90)
			(unlocked yes)
			(layer "B.Fab")
			(hide yes)
			(effects
				(font
					(size 1 1)
					(thickness 0.15)
				)
				(justify mirror)
			)
		)
		(property "License" "Apache-2.0"
			(at 0 0 90)
			(unlocked yes)
			(layer "B.Fab")
			(hide yes)
			(effects
				(font
					(size 1 1)
					(thickness 0.15)
				)
				(justify mirror)
			)
		)
		(property "Author" "Antmicro"
			(at 0 0 90)
			(unlocked yes)
			(layer "B.Fab")
			(hide yes)
			(effects
				(font
					(size 1 1)
					(thickness 0.15)
				)
				(justify mirror)
			)
		)
		(property "Val" "1u"
			(at 0 0 90)
			(unlocked yes)
			(layer "B.Fab")
			(hide yes)
			(effects
				(font
					(size 1 1)
					(thickness 0.15)
				)
				(justify mirror)
			)
		)
		(property "Voltage" "25V"
			(at 0 0 90)
			(unlocked yes)
			(layer "B.Fab")
			(hide yes)
			(effects
				(font
					(size 1 1)
					(thickness 0.15)
				)
				(justify mirror)
			)
		)
		(property "Dielectric" "X5R"
			(at 0 0 90)
			(unlocked yes)
			(layer "B.Fab")
			(hide yes)
			(effects
				(font
					(size 1 1)
					(thickness 0.15)
				)
				(justify mirror)
			)
		)
		(sheetname "/X710-AT2 power/")
		(sheetfile "x710-at2-power.kicad_sch")
		(attr smd)
		(fp_rect
			(start -0.925 0.47)
			(end 0.925 -0.47)
			(stroke
				(width 0.05)
				(type default)
			)
			(fill no)
			(layer "B.CrtYd")
		)
		(fp_line
			(start 0.504 -0.248)
			(end -0.494 -0.248)
			(stroke
				(width 0.15)
				(type solid)
			)
			(layer "B.Fab")
		)
		(fp_line
			(start -0.494 -0.248)
			(end -0.494 0.25)
			(stroke
				(width 0.15)
				(type solid)
			)
			(layer "B.Fab")
		)
		(fp_line
			(start 0.504 0.25)
			(end 0.504 -0.248)
			(stroke
				(width 0.15)
				(type solid)
			)
			(layer "B.Fab")
		)
		(fp_line
			(start -0.494 0.25)
			(end 0.504 0.25)
			(stroke
				(width 0.15)
				(type solid)
			)
			(layer "B.Fab")
		)
		(pad "1" smd roundrect
			(at -0.48 0 90)
			(size 0.59 0.64)
			(layers "B.Cu" "B.Mask" "B.Paste")
			(roundrect_rratio 0.25)
			(net 28 "GND")
			(pintype "passive")
		)
		(pad "2" smd roundrect
			(at 0.48 0 90)
			(size 0.59 0.64)
			(layers "B.Cu" "B.Mask" "B.Paste")
			(roundrect_rratio 0.25)
			(net 1 "VCCA")
			(pintype "passive")
		)
	)
)
